(kicad_pcb
	(version 20241229)
	(generator "pcbnew")
	(generator_version "9.0")
	(general
		(thickness 1.62)
		(legacy_teardrops no)
	)
	(paper "A3")
	(title_block
		(title "COM Express 7 Baseboard")
		(date "2025-02-04")
		(rev "1.1.2")
		(company "Antmicro Ltd")
		(comment 1 "www.antmicro.com")
		(comment 9 "footprints 498-502 of 802")
	)
	(layers
		(0 "F.Cu" signal)
		(4 "In1.Cu" signal)
		(6 "In2.Cu" signal)
		(8 "In3.Cu" signal)
		(10 "In4.Cu" signal)
		(12 "In5.Cu" signal)
		(14 "In6.Cu" signal)
		(2 "B.Cu" signal)
		(9 "F.Adhes" user "F.Adhesive")
		(11 "B.Adhes" user "B.Adhesive")
		(13 "F.Paste" user)
		(15 "B.Paste" user)
		(5 "F.SilkS" user "F.Silkscreen")
		(7 "B.SilkS" user "B.Silkscreen")
		(1 "F.Mask" user)
		(3 "B.Mask" user)
		(17 "Dwgs.User" user "User.Drawings")
		(19 "Cmts.User" user "User.Comments")
		(21 "Eco1.User" user "User.Eco1")
		(23 "Eco2.User" user "User.Eco2")
		(25 "Edge.Cuts" user)
		(27 "Margin" user)
		(31 "F.CrtYd" user "F.Courtyard")
		(29 "B.CrtYd" user "B.Courtyard")
		(35 "F.Fab" user)
		(33 "B.Fab" user)
	)
	(footprint "antmicro-footprints:L_Coilcraft-XAL6030"
		(layer "F.Cu")
		(at 311.064999 110.96 180)
		(property "Reference" "L2"
			(at 4.864999 -0.35 0)
			(unlocked yes)
			(layer "F.SilkS")
			(effects
				(font
					(size 0.7 0.7)
					(thickness 0.15)
				)
				(justify left bottom)
			)
		)
		(property "Value" "L_1u8_14A_Coilcraft-XAL6030"
			(at 0 4.7 180)
			(unlocked yes)
			(layer "F.Fab")
			(effects
				(font
					(size 0.7 0.7)
					(thickness 0.15)
				)
				(justify left bottom)
			)
		)
		(property "Datasheet" "https://www.mouser.com/datasheet/2/597/xal60xx-270658.pdf"
			(at 0 0 180)
			(layer "F.Fab")
			(hide yes)
			(effects
				(font
					(size 1.27 1.27)
					(thickness 0.15)
				)
			)
		)
		(property "Author" "Antmicro"
			(at 622.129998 221.92 0)
			(layer "F.Fab")
			(hide yes)
			(effects
				(font
					(size 1 1)
					(thickness 0.15)
				)
			)
		)
		(property "IMax" "14 A"
			(at 622.129998 221.92 0)
			(layer "F.Fab")
			(hide yes)
			(effects
				(font
					(size 1 1)
					(thickness 0.15)
				)
			)
		)
		(property "ISat" "18.2 A"
			(at 622.129998 221.92 0)
			(layer "F.Fab")
			(hide yes)
			(effects
				(font
					(size 1 1)
					(thickness 0.15)
				)
			)
		)
		(property "License" "Apache-2.0"
			(at 622.129998 221.92 0)
			(layer "F.Fab")
			(hide yes)
			(effects
				(font
					(size 1 1)
					(thickness 0.15)
				)
			)
		)
		(property "MPN" "XAL6030-182MEC"
			(at 622.129998 221.92 0)
			(layer "F.Fab")
			(hide yes)
			(effects
				(font
					(size 1 1)
					(thickness 0.15)
				)
			)
		)
		(property "Manufacturer" "Coilcraft"
			(at 622.129998 221.92 0)
			(layer "F.Fab")
			(hide yes)
			(effects
				(font
					(size 1 1)
					(thickness 0.15)
				)
			)
		)
		(property "Public" "False"
			(at 622.129998 221.92 0)
			(layer "F.Fab")
			(hide yes)
			(effects
				(font
					(size 1 1)
					(thickness 0.15)
				)
			)
		)
		(property "Size" "6.36x6.56"
			(at 622.129998 221.92 0)
			(layer "F.Fab")
			(hide yes)
			(effects
				(font
					(size 1 1)
					(thickness 0.15)
				)
			)
		)
		(property "Val" "1.8u/14A"
			(at 622.129998 221.92 0)
			(layer "F.Fab")
			(hide yes)
			(effects
				(font
					(size 1 1)
					(thickness 0.15)
				)
			)
		)
		(sheetname "Power")
		(sheetfile "power.kicad_sch")
		(attr smd)
		(fp_rect
			(start -3.299 -3.4)
			(end 3.299 3.4)
			(stroke
				(width 0.15)
				(type solid)
			)
			(fill no)
			(layer "F.SilkS")
		)
		(fp_rect
			(start -3.52 -3.63)
			(end 3.52 3.63)
			(stroke
				(width 0.05)
				(type solid)
			)
			(fill no)
			(layer "F.CrtYd")
		)
		(fp_rect
			(start -3.279 -3.38)
			(end 3.279 3.38)
			(stroke
				(width 0.15)
				(type solid)
			)
			(fill no)
			(layer "F.Fab")
		)
		(pad "1" smd roundrect
			(at -2.02 0 180)
			(size 1.43 5.5)
			(layers "F.Cu" "F.Mask" "F.Paste")
			(roundrect_rratio 0.1)
			(net 69 "Net-(C48-Pad2)")
			(pintype "passive")
			(teardrops
				(best_length_ratio 0.2)
				(max_length 1)
				(best_width_ratio 0.9)
				(max_width 2)
				(curved_edges yes)
				(filter_ratio 0.9)
				(enabled yes)
				(allow_two_segments yes)
				(prefer_zone_connections yes)
			)
		)
		(pad "2" smd roundrect
			(at 2.019 0 180)
			(size 1.43 5.5)
			(layers "F.Cu" "F.Mask" "F.Paste")
			(roundrect_rratio 0.1)
			(net 71 "Net-(U49-IN+)")
			(pintype "passive")
			(teardrops
				(best_length_ratio 0.2)
				(max_length 1)
				(best_width_ratio 0.9)
				(max_width 2)
				(curved_edges yes)
				(filter_ratio 0.9)
				(enabled yes)
				(allow_two_segments yes)
				(prefer_zone_connections yes)
			)
		)
	)
	(footprint "antmicro-footprints:TP_SMD_0.75mm"
		(layer "F.Cu")
		(at 196.057538 132.257538 45)
		(property "Reference" "TP53"
			(at 0.4 0.45 45)
			(layer "F.SilkS")
			(effects
				(font
					(size 0.7 0.7)
					(thickness 0.15)
				)
				(justify left bottom)
			)
		)
		(property "Value" "TP_0.75mm_SMD"
			(at 0 1.2 45)
			(layer "F.Fab")
			(effects
				(font
					(size 0.7 0.7)
					(thickness 0.15)
				)
				(justify left bottom)
			)
		)
		(property "Author" "Antmicro"
			(at 369.6 -269.12 45)
			(layer "F.Fab")
			(hide yes)
			(effects
				(font
					(size 1 1)
					(thickness 0.15)
				)
			)
		)
		(property "License" "Apache-2.0"
			(at 369.6 -269.12 45)
			(layer "F.Fab")
			(hide yes)
			(effects
				(font
					(size 1 1)
					(thickness 0.15)
				)
			)
		)
		(property "MPN" ""
			(at 369.6 -269.12 45)
			(layer "F.Fab")
			(hide yes)
			(effects
				(font
					(size 1 1)
					(thickness 0.15)
				)
			)
		)
		(property "Manufacturer" ""
			(at 369.6 -269.12 45)
			(layer "F.Fab")
			(hide yes)
			(effects
				(font
					(size 1 1)
					(thickness 0.15)
				)
			)
		)
		(property "Public" "False"
			(at 369.6 -269.12 45)
			(layer "F.Fab")
			(hide yes)
			(effects
				(font
					(size 1 1)
					(thickness 0.15)
				)
			)
		)
		(sheetname "PCIe redriver")
		(sheetfile "pcie_redriver.kicad_sch")
		(attr exclude_from_pos_files exclude_from_bom)
		(fp_circle
			(center 0 0)
			(end 0.475 0)
			(stroke
				(width 0.05)
				(type default)
			)
			(fill no)
			(layer "F.CrtYd")
		)
		(pad "1" smd circle
			(at 0 0 45)
			(size 0.75 0.75)
			(layers "F.Cu" "F.Mask")
			(net 716 "Net-(U40-SDA)")
			(pinfunction "1")
			(pintype "passive")
			(teardrops
				(best_length_ratio 0.4)
				(max_length 1)
				(best_width_ratio 0.9)
				(max_width 2)
				(curved_edges yes)
				(filter_ratio 0.9)
				(enabled yes)
				(allow_two_segments yes)
				(prefer_zone_connections yes)
			)
		)
	)
	(footprint "antmicro-footprints:SOT-23-3"
		(layer "F.Cu")
		(at 261.42 161.58 180)
		(property "Reference" "D21"
			(at 0.32 -1.72 90)
			(layer "F.SilkS")
			(effects
				(font
					(size 0.7 0.7)
					(thickness 0.15)
				)
				(justify right top)
			)
		)
		(property "Value" "BAT54C"
			(at -1.9 2.7 0)
			(layer "F.Fab")
			(effects
				(font
					(size 0.7 0.7)
					(thickness 0.15)
				)
				(justify right top)
			)
		)
		(property "Datasheet" "https://diotec.com/request/datasheet/bat54.pdf"
			(at 0 0 0)
			(layer "F.Fab")
			(hide yes)
			(effects
				(font
					(size 1.27 1.27)
					(thickness 0.15)
				)
			)
		)
		(property "Author" "Antmicro"
			(at 317.61 -19.19 90)
			(layer "F.Fab")
			(hide yes)
			(effects
				(font
					(size 1 1)
					(thickness 0.15)
				)
			)
		)
		(property "License" "Apache-2.0"
			(at 317.61 -19.19 90)
			(layer "F.Fab")
			(hide yes)
			(effects
				(font
					(size 1 1)
					(thickness 0.15)
				)
			)
		)
		(property "MPN" "BAT54C"
			(at 317.61 -19.19 90)
			(layer "F.Fab")
			(hide yes)
			(effects
				(font
					(size 1 1)
					(thickness 0.15)
				)
			)
		)
		(property "Manufacturer" "Diotec Semiconductor"
			(at 317.61 -19.19 90)
			(layer "F.Fab")
			(hide yes)
			(effects
				(font
					(size 1 1)
					(thickness 0.15)
				)
			)
		)
		(sheetname "Com Express 7 MGMT")
		(sheetfile "com_express_7_mgmt.kicad_sch")
		(attr smd)
		(fp_line
			(start 0.7 1.5)
			(end -0.7 1.5)
			(stroke
				(width 0.15)
				(type solid)
			)
			(layer "F.SilkS")
		)
		(fp_line
			(start 0.7 0.4)
			(end 0.7 1.5)
			(stroke
				(width 0.15)
				(type solid)
			)
			(layer "F.SilkS")
		)
		(fp_line
			(start 0.7 -0.4)
			(end 0.7 -1.5)
			(stroke
				(width 0.15)
				(type solid)
			)
			(layer "F.SilkS")
		)
		(fp_line
			(start 0.7 -1.5)
			(end -0.7 -1.5)
			(stroke
				(width 0.15)
				(type solid)
			)
			(layer "F.SilkS")
		)
		(fp_line
			(start -0.7 1.5)
			(end -0.7 1.35)
			(stroke
				(width 0.15)
				(type solid)
			)
			(layer "F.SilkS")
		)
		(fp_line
			(start -0.85 -1.35)
			(end -0.7 -1.5)
			(stroke
				(width 0.15)
				(type solid)
			)
			(layer "F.SilkS")
		)
		(fp_line
			(start -1.45 -1.35)
			(end -0.85 -1.35)
			(stroke
				(width 0.15)
				(type solid)
			)
			(layer "F.SilkS")
		)
		(fp_line
			(start 1.75 0.45)
			(end 0.85 0.45)
			(stroke
				(width 0.05)
				(type solid)
			)
			(layer "F.CrtYd")
		)
		(fp_line
			(start 1.75 -0.45)
			(end 1.75 0.45)
			(stroke
				(width 0.05)
				(type solid)
			)
			(layer "F.CrtYd")
		)
		(fp_line
			(start 0.85 1.65)
			(end -0.85 1.65)
			(stroke
				(width 0.05)
				(type solid)
			)
			(layer "F.CrtYd")
		)
		(fp_line
			(start 0.85 0.45)
			(end 0.85 1.65)
			(stroke
				(width 0.05)
				(type solid)
			)
			(layer "F.CrtYd")
		)
		(fp_line
			(start 0.825 -0.45)
			(end 1.75 -0.45)
			(stroke
				(width 0.05)
				(type solid)
			)
			(layer "F.CrtYd")
		)
		(fp_line
			(start 0.825 -1.6)
			(end 0.825 -0.45)
			(stroke
				(width 0.05)
				(type solid)
			)
			(layer "F.CrtYd")
		)
		(fp_line
			(start -0.85 1.65)
			(end -0.85 1.4)
			(stroke
				(width 0.05)
				(type solid)
			)
			(layer "F.CrtYd")
		)
		(fp_line
			(start -0.85 1.4)
			(end -1.75 1.4)
			(stroke
				(width 0.05)
				(type solid)
			)
			(layer "F.CrtYd")
		)
		(fp_line
			(start -0.85 0.5)
			(end -0.85 -0.5)
			(stroke
				(width 0.05)
				(type solid)
			)
			(layer "F.CrtYd")
		)
		(fp_line
			(start -0.85 -0.5)
			(end -1.75 -0.5)
			(stroke
				(width 0.05)
				(type solid)
			)
			(layer "F.CrtYd")
		)
		(fp_line
			(start -0.9 -1.4)
			(end -1.75 -1.4)
			(stroke
				(width 0.05)
				(type solid)
			)
			(layer "F.CrtYd")
		)
		(fp_line
			(start -0.9 -1.6)
			(end 0.825 -1.6)
			(stroke
				(width 0.05)
				(type solid)
			)
			(layer "F.CrtYd")
		)
		(fp_line
			(start -0.9 -1.6)
			(end -0.9 -1.4)
			(stroke
				(width 0.05)
				(type solid)
			)
			(layer "F.CrtYd")
		)
		(fp_line
			(start -1.75 1.4)
			(end -1.75 0.5)
			(stroke
				(width 0.05)
				(type solid)
			)
			(layer "F.CrtYd")
		)
		(fp_line
			(start -1.75 0.5)
			(end -0.85 0.5)
			(stroke
				(width 0.05)
				(type solid)
			)
			(layer "F.CrtYd")
		)
		(fp_line
			(start -1.75 -0.5)
			(end -1.75 -1.4)
			(stroke
				(width 0.05)
				(type solid)
			)
			(layer "F.CrtYd")
		)
		(fp_line
			(start 0.688 1.519)
			(end 0.688 -1.52)
			(stroke
				(width 0.15)
				(type solid)
			)
			(layer "F.Fab")
		)
		(fp_line
			(start -0.437 -1.526)
			(end 0.688 -1.526)
			(stroke
				(width 0.15)
				(type solid)
			)
			(layer "F.Fab")
		)
		(fp_line
			(start -0.437 -1.526)
			(end -0.712 -1.325)
			(stroke
				(width 0.15)
				(type solid)
			)
			(layer "F.Fab")
		)
		(fp_line
			(start -0.712 1.519)
			(end 0.688 1.519)
			(stroke
				(width 0.15)
				(type solid)
			)
			(layer "F.Fab")
		)
		(fp_line
			(start -0.712 -1.325)
			(end -0.712 1.523)
			(stroke
				(width 0.15)
				(type solid)
			)
			(layer "F.Fab")
		)
		(pad "1" smd roundrect
			(at -1.1 -0.951 180)
			(size 1 0.6)
			(layers "F.Cu" "F.Mask" "F.Paste")
			(roundrect_rratio 0.15)
			(net 139 "/Com Express 7 MGMT/SPI_POWER")
			(pinfunction "1")
			(pintype "passive")
			(teardrops
				(best_length_ratio 0.2)
				(max_length 1)
				(best_width_ratio 0.9)
				(max_width 2)
				(curved_edges yes)
				(filter_ratio 0.9)
				(enabled yes)
				(allow_two_segments yes)
				(prefer_zone_connections yes)
			)
		)
		(pad "2" smd roundrect
			(at -1.1 0.949 180)
			(size 1 0.6)
			(layers "F.Cu" "F.Mask" "F.Paste")
			(roundrect_rratio 0.15)
			(net 140 "unconnected-(D21-Pad2)")
			(pinfunction "2")
			(pintype "passive+no_connect")
			(teardrops
				(best_length_ratio 0.2)
				(max_length 1)
				(best_width_ratio 0.9)
				(max_width 2)
				(curved_edges yes)
				(filter_ratio 0.9)
				(enabled yes)
				(allow_two_segments yes)
				(prefer_zone_connections yes)
			)
		)
		(pad "3" smd roundrect
			(at 1.1 -0.0005 180)
			(size 1 0.6)
			(layers "F.Cu" "F.Mask" "F.Paste")
			(roundrect_rratio 0.15)
			(net 85 "/Com Express 7 MGMT/MAFS_POWER")
			(pinfunction "3")
			(pintype "passive")
			(teardrops
				(best_length_ratio 0.2)
				(max_length 1)
				(best_width_ratio 0.9)
				(max_width 2)
				(curved_edges yes)
				(filter_ratio 0.9)
				(enabled yes)
				(allow_two_segments yes)
				(prefer_zone_connections yes)
			)
		)
	)
	(footprint "antmicro-footprints:R_0402_1005Metric"
		(layer "F.Cu")
		(at 178.4 148 180)
		(descr "Resistor SMD 0402")
		(tags "resistor SMD 0402")
		(property "Reference" "R41"
			(at -2.95 -0.45 0)
			(layer "F.SilkS")
			(effects
				(font
					(size 0.7 0.7)
					(thickness 0.15)
				)
				(justify right bottom)
			)
		)
		(property "Value" "R_0R_0402"
			(at -1.011843 1.772046 0)
			(layer "F.Fab")
			(effects
				(font
					(size 0.7 0.7)
					(thickness 0.15)
				)
				(justify right bottom)
			)
		)
		(property "Datasheet" "https://industrial.panasonic.com/cdbs/www-data/pdf/RDA0000/AOA0000C301.pdf"
			(at 0 0 0)
			(layer "F.Fab")
			(hide yes)
			(effects
				(font
					(size 1.27 1.27)
					(thickness 0.15)
				)
			)
		)
		(property "Author" "Antmicro"
			(at 337.899999 336.52 0)
			(layer "F.Fab")
			(hide yes)
			(effects
				(font
					(size 1 1)
					(thickness 0.15)
				)
			)
		)
		(property "Current" "1A"
			(at 337.899999 336.52 0)
			(layer "F.Fab")
			(hide yes)
			(effects
				(font
					(size 1 1)
					(thickness 0.15)
				)
			)
		)
		(property "License" "Apache-2.0"
			(at 337.899999 336.52 0)
			(layer "F.Fab")
			(hide yes)
			(effects
				(font
					(size 1 1)
					(thickness 0.15)
				)
			)
		)
		(property "MPN" "ERJ2GE0R00X"
			(at 337.899999 336.52 0)
			(layer "F.Fab")
			(hide yes)
			(effects
				(font
					(size 1 1)
					(thickness 0.15)
				)
			)
		)
		(property "Manufacturer" "Panasonic"
			(at 337.899999 336.52 0)
			(layer "F.Fab")
			(hide yes)
			(effects
				(font
					(size 1 1)
					(thickness 0.15)
				)
			)
		)
		(property "Public" "False"
			(at 337.899999 336.52 0)
			(layer "F.Fab")
			(hide yes)
			(effects
				(font
					(size 1 1)
					(thickness 0.15)
				)
			)
		)
		(property "Tolerance" ""
			(at 337.899999 336.52 0)
			(layer "F.Fab")
			(hide yes)
			(effects
				(font
					(size 1 1)
					(thickness 0.15)
				)
			)
		)
		(property "Val" "0R"
			(at 337.899999 336.52 0)
			(layer "F.Fab")
			(hide yes)
			(effects
				(font
					(size 1 1)
					(thickness 0.15)
				)
			)
		)
		(sheetname "2xSFP+")
		(sheetfile "2xSFP+.kicad_sch")
		(attr smd)
		(fp_rect
			(start -0.925 -0.47)
			(end 0.925 0.47)
			(stroke
				(width 0.05)
				(type default)
			)
			(fill no)
			(layer "F.CrtYd")
		)
		(fp_rect
			(start -0.5 -0.25)
			(end 0.5 0.25)
			(stroke
				(width 0.15)
				(type solid)
			)
			(fill no)
			(layer "F.Fab")
		)
		(pad "1" smd roundrect
			(at -0.48 0 180)
			(size 0.59 0.64)
			(layers "F.Cu" "F.Mask" "F.Paste")
			(roundrect_rratio 0.25)
			(net 487 "/2xSFP+/I2C_{SFP1}.SCL")
			(pintype "passive")
			(teardrops
				(best_length_ratio 0.2)
				(max_length 1)
				(best_width_ratio 0.9)
				(max_width 2)
				(curved_edges yes)
				(filter_ratio 0.9)
				(enabled yes)
				(allow_two_segments yes)
				(prefer_zone_connections yes)
			)
		)
		(pad "2" smd roundrect
			(at 0.48 0 180)
			(size 0.59 0.64)
			(layers "F.Cu" "F.Mask" "F.Paste")
			(roundrect_rratio 0.25)
			(net 875 "/2xSFP+/SCL1")
			(pintype "passive")
			(teardrops
				(best_length_ratio 0.2)
				(max_length 1)
				(best_width_ratio 0.9)
				(max_width 2)
				(curved_edges yes)
				(filter_ratio 0.9)
				(enabled yes)
				(allow_two_segments yes)
				(prefer_zone_connections yes)
			)
		)
	)
	(footprint "antmicro-footprints:R_0402_1005Metric"
		(layer "F.Cu")
		(at 309.174999 120.16 -90)
		(descr "Resistor SMD 0402")
		(tags "resistor SMD 0402")
		(property "Reference" "R98"
			(at -1.1 0.524999 270)
			(layer "F.SilkS")
			(effects
				(font
					(size 0.7 0.7)
					(thickness 0.15)
				)
				(justify right bottom)
			)
		)
		(property "Value" "R_15k_0402"
			(at -1.011843 1.772047 90)
			(layer "F.Fab")
			(effects
				(font
					(size 0.7 0.7)
					(thickness 0.15)
				)
				(justify right bottom)
			)
		)
		(property "Datasheet" "https://www.bourns.com/docs/product-datasheets/cr.pdf"
			(at 0 0 270)
			(layer "F.Fab")
			(hide yes)
			(effects
				(font
					(size 1.27 1.27)
					(thickness 0.15)
				)
			)
		)
		(property "Author" "Antmicro"
			(at 189.014999 429.334999 0)
			(layer "F.Fab")
			(hide yes)
			(effects
				(font
					(size 1 1)
					(thickness 0.15)
				)
			)
		)
		(property "License" "Apache-2.0"
			(at 189.014999 429.334999 0)
			(layer "F.Fab")
			(hide yes)
			(effects
				(font
					(size 1 1)
					(thickness 0.15)
				)
			)
		)
		(property "MPN" "CR0402-FX-1502GLF"
			(at 189.014999 429.334999 0)
			(layer "F.Fab")
			(hide yes)
			(effects
				(font
					(size 1 1)
					(thickness 0.15)
				)
			)
		)
		(property "Manufacturer" "Bourns"
			(at 189.014999 429.334999 0)
			(layer "F.Fab")
			(hide yes)
			(effects
				(font
					(size 1 1)
					(thickness 0.15)
				)
			)
		)
		(property "Public" "False"
			(at 189.014999 429.334999 0)
			(layer "F.Fab")
			(hide yes)
			(effects
				(font
					(size 1 1)
					(thickness 0.15)
				)
			)
		)
		(property "Tolerance" "1%"
			(at 189.014999 429.334999 0)
			(layer "F.Fab")
			(hide yes)
			(effects
				(font
					(size 1 1)
					(thickness 0.15)
				)
			)
		)
		(property "Val" "15k"
			(at 189.014999 429.334999 0)
			(layer "F.Fab")
			(hide yes)
			(effects
				(font
					(size 1 1)
					(thickness 0.15)
				)
			)
		)
		(sheetname "Power")
		(sheetfile "power.kicad_sch")
		(attr smd)
		(fp_rect
			(start -0.925 -0.47)
			(end 0.925 0.47)
			(stroke
				(width 0.05)
				(type default)
			)
			(fill no)
			(layer "F.CrtYd")
		)
		(fp_rect
			(start -0.5 -0.25)
			(end 0.5 0.25)
			(stroke
				(width 0.15)
				(type solid)
			)
			(fill no)
			(layer "F.Fab")
		)
		(pad "1" smd roundrect
			(at -0.48 0 270)
			(size 0.59 0.64)
			(layers "F.Cu" "F.Mask" "F.Paste")
			(roundrect_rratio 0.25)
			(net 1 "GND")
			(pintype "passive")
			(teardrops
				(best_length_ratio 0.2)
				(max_length 1)
				(best_width_ratio 0.9)
				(max_width 2)
				(curved_edges yes)
				(filter_ratio 0.9)
				(enabled yes)
				(allow_two_segments yes)
				(prefer_zone_connections yes)
			)
		)
		(pad "2" smd roundrect
			(at 0.48 0 270)
			(size 0.59 0.64)
			(layers "F.Cu" "F.Mask" "F.Paste")
			(roundrect_rratio 0.25)
			(net 580 "Net-(U18-FB)")
			(pintype "passive")
			(teardrops
				(best_length_ratio 0.2)
				(max_length 1)
				(best_width_ratio 0.9)
				(max_width 2)
				(curved_edges yes)
				(filter_ratio 0.9)
				(enabled yes)
				(allow_two_segments yes)
				(prefer_zone_connections yes)
			)
		)
	)
)
